# BASEBOARD_FAB2 (Tioga Pass) — schematic netlist excerpt (pin names and nets, part order shuffled) for the footprints in the layout excerpt that follows; sources: Cadence DE-HDL packaged netlist, KiCad conversion of Wiwynn_Tioga_Pass_MB.brd

C1R9  CAP  0.22UF 16V 10% X7R  pkg 0402  page 106 : A = P3E_CPU0_PE3_OCP_TXN<4> ; B = P3E_OCP_CPU0_PE3_C_TXN<4>
C3M3  CAP  0.22UF 16V 10% X7R  pkg 0402  page 105 : A = P3E_CPU0_PE1_PCH_R_RXP<12> ; B = P3E_CPU0_PE1_PCH_RXP<12>
C8P17  CAP  47UF 4V 20% X6S  pkg 0805  page 76 : A = PVCCIN_CPU1 ; B = GND

(kicad_pcb
	(version 20260206)
	(generator "pcbnew")
	(generator_version "10.0")
	(general
		(thickness 1.6)
		(legacy_teardrops no)
	)
	(paper "A4")
	(title_block
		(title "Wiwynn_Tioga_Pass_MB.brd")
		(comment 1 "Tioga Pass / footprints 3004-3006 of 4770")
	)
	(layers
		(0 "F.Cu" signal "TOP")
		(4 "In1.Cu" signal "L2GND")
		(6 "In2.Cu" signal "L3")
		(8 "In3.Cu" signal "L4GND")
		(10 "In4.Cu" signal "L5")
		(12 "In5.Cu" signal "L6GND")
		(14 "In6.Cu" signal "L7VCC")
		(16 "In7.Cu" signal "L8VCC")
		(18 "In8.Cu" signal "L9GND")
		(20 "In9.Cu" signal "L10")
		(22 "In10.Cu" signal "L11GND")
		(24 "In11.Cu" signal "L12")
		(26 "In12.Cu" signal "L13GND")
		(2 "B.Cu" signal "BOTTOM")
		(9 "F.Adhes" user "F.Adhesive")
		(11 "B.Adhes" user "B.Adhesive")
		(13 "F.Paste" user "Package Geometry/Pastemask Top")
		(15 "B.Paste" user "Package Geometry/Pastemask Bottom")
		(5 "F.SilkS" user "Ref Des/Silkscreen Top")
		(7 "B.SilkS" user "Ref Des/Silkscreen Bottom")
		(1 "F.Mask" user "Board Geometry/Soldermask Top")
		(3 "B.Mask" user "Board Geometry/Soldermask Bottom")
		(17 "Dwgs.User" user "User.Drawings")
		(19 "Cmts.User" user "User.Comments")
		(21 "Eco1.User" user "User.Eco1")
		(23 "Eco2.User" user "User.Eco2")
		(25 "Edge.Cuts" user "Board Geometry/Outline")
		(27 "Margin" user)
		(31 "F.CrtYd" user "Package Geometry/Place Bound Top")
		(29 "B.CrtYd" user "Package Geometry/Place Bound Bottom")
		(35 "F.Fab" user "Ref Des/Assembly Top")
		(33 "B.Fab" user "Ref Des/Assembly Bottom")
	)
	(footprint ""
		(layer "B.Cu")
		(at 450.98335 -52.407058)
		(property "Reference" "C1R9"
			(at 0 0 0)
			(layer "B.SilkS")
			(hide yes)
			(effects
				(font
					(size 1.27 1.27)
				)
				(justify mirror)
			)
		)
		(property "Value" ""
			(at 0 0 0)
			(layer "B.Fab")
			(effects
				(font
					(size 1.27 1.27)
				)
				(justify mirror)
			)
		)
		(duplicate_pad_numbers_are_jumpers no)
		(fp_poly
			(pts
				(xy -0.3048 -0.1016) (xy -0.3048 0.9906) (xy 0.3048 0.9906) (xy 0.3048 -0.1016)
			)
			(stroke
				(width 0)
				(type default)
			)
			(fill no)
			(layer "B.CrtYd")
		)
		(fp_line
			(start -0.3048 -0.1016)
			(end 0.3048 -0.1016)
			(stroke
				(width 0.1)
				(type default)
			)
			(layer "B.Fab")
		)
		(fp_line
			(start -0.3048 0.9906)
			(end -0.3048 -0.1016)
			(stroke
				(width 0.1)
				(type default)
			)
			(layer "B.Fab")
		)
		(fp_line
			(start 0.3048 -0.1016)
			(end 0.3048 0.9906)
			(stroke
				(width 0.1)
				(type default)
			)
			(layer "B.Fab")
		)
		(fp_line
			(start 0.3048 0.9906)
			(end -0.3048 0.9906)
			(stroke
				(width 0.1)
				(type default)
			)
			(layer "B.Fab")
		)
		(pad "1" smd rect
			(at 0 0 180)
			(size 0.508 0.508)
			(layers "B.Cu" "B.Mask" "B.Paste")
			(net "P3E_CPU0_PE3_OCP_TXN<4>")
		)
		(pad "2" smd rect
			(at 0 0.889 180)
			(size 0.508 0.508)
			(layers "B.Cu" "B.Mask" "B.Paste")
			(net "P3E_OCP_CPU0_PE3_C_TXN<4>")
		)
		(zone
			(layer "B.Cu")
			(hatch none 0.5)
			(connect_pads
				(clearance 0)
			)
			(min_thickness 0.25)
			(keepout
				(tracks allowed)
				(vias not_allowed)
				(pads allowed)
				(copperpour not_allowed)
				(footprints allowed)
			)
			(placement
				(enabled no)
				(sheetname "")
			)
			(fill
				(thermal_gap 0.5)
				(thermal_bridge_width 0.5)
				(island_removal_mode 0)
			)
			(polygon
				(pts
					(xy 451.23735 -52.153058) (xy 450.72935 -52.153058) (xy 450.72935 -51.772058) (xy 451.23735 -51.772058)
				)
			)
		)
		(zone
			(layer "B.Cu")
			(hatch none 0.5)
			(connect_pads
				(clearance 0)
			)
			(min_thickness 0.25)
			(keepout
				(tracks not_allowed)
				(vias allowed)
				(pads allowed)
				(copperpour not_allowed)
				(footprints allowed)
			)
			(placement
				(enabled no)
				(sheetname "")
			)
			(fill
				(thermal_gap 0.5)
				(thermal_bridge_width 0.5)
				(island_removal_mode 0)
			)
			(polygon
				(pts
					(xy 451.23735 -51.772058) (xy 450.72935 -51.772058) (xy 450.72935 -52.153058) (xy 451.23735 -52.153058)
				)
			)
		)
	)
	(footprint ""
		(layer "B.Cu")
		(at 354.543614 -122.662442 -90)
		(property "Reference" "C3M3"
			(at 0 0 90)
			(layer "B.SilkS")
			(hide yes)
			(effects
				(font
					(size 1.27 1.27)
				)
				(justify mirror)
			)
		)
		(property "Value" ""
			(at 0 0 90)
			(layer "B.Fab")
			(effects
				(font
					(size 1.27 1.27)
				)
				(justify mirror)
			)
		)
		(duplicate_pad_numbers_are_jumpers no)
		(fp_poly
			(pts
				(xy -0.3048 -0.1016) (xy -0.3048 0.9906) (xy 0.3048 0.9906) (xy 0.3048 -0.1016)
			)
			(stroke
				(width 0)
				(type default)
			)
			(fill no)
			(layer "B.CrtYd")
		)
		(fp_line
			(start -0.3048 0.9906)
			(end -0.3048 -0.1016)
			(stroke
				(width 0.1)
				(type default)
			)
			(layer "B.Fab")
		)
		(fp_line
			(start 0.3048 0.9906)
			(end -0.3048 0.9906)
			(stroke
				(width 0.1)
				(type default)
			)
			(layer "B.Fab")
		)
		(fp_line
			(start -0.3048 -0.1016)
			(end 0.3048 -0.1016)
			(stroke
				(width 0.1)
				(type default)
			)
			(layer "B.Fab")
		)
		(fp_line
			(start 0.3048 -0.1016)
			(end 0.3048 0.9906)
			(stroke
				(width 0.1)
				(type default)
			)
			(layer "B.Fab")
		)
		(pad "1" smd rect
			(at 0 0 90)
			(size 0.508 0.508)
			(layers "B.Cu" "B.Mask" "B.Paste")
			(net "P3E_CPU0_PE1_PCH_R_RXP<12>")
		)
		(pad "2" smd rect
			(at 0 0.889 90)
			(size 0.508 0.508)
			(layers "B.Cu" "B.Mask" "B.Paste")
			(net "P3E_CPU0_PE1_PCH_RXP<12>")
		)
		(zone
			(layer "B.Cu")
			(hatch none 0.5)
			(connect_pads
				(clearance 0)
			)
			(min_thickness 0.25)
			(keepout
				(tracks not_allowed)
				(vias allowed)
				(pads allowed)
				(copperpour not_allowed)
				(footprints allowed)
			)
			(placement
				(enabled no)
				(sheetname "")
			)
			(fill
				(thermal_gap 0.5)
				(thermal_bridge_width 0.5)
				(island_removal_mode 0)
			)
			(polygon
				(pts
					(xy 353.908614 -122.408442) (xy 353.908614 -122.916442) (xy 354.289614 -122.916442) (xy 354.289614 -122.408442)
				)
			)
		)
		(zone
			(layer "B.Cu")
			(hatch none 0.5)
			(connect_pads
				(clearance 0)
			)
			(min_thickness 0.25)
			(keepout
				(tracks allowed)
				(vias not_allowed)
				(pads allowed)
				(copperpour not_allowed)
				(footprints allowed)
			)
			(placement
				(enabled no)
				(sheetname "")
			)
			(fill
				(thermal_gap 0.5)
				(thermal_bridge_width 0.5)
				(island_removal_mode 0)
			)
			(polygon
				(pts
					(xy 354.289614 -122.408442) (xy 354.289614 -122.916442) (xy 353.908614 -122.916442) (xy 353.908614 -122.408442)
				)
			)
		)
	)
	(footprint ""
		(layer "B.Cu")
		(at 100.863654 -77.82814)
		(property "Reference" "C8P17"
			(at 0 0 0)
			(layer "B.SilkS")
			(hide yes)
			(effects
				(font
					(size 1.27 1.27)
				)
				(justify mirror)
			)
		)
		(property "Value" ""
			(at 0 0 0)
			(layer "B.Fab")
			(effects
				(font
					(size 1.27 1.27)
				)
				(justify mirror)
			)
		)
		(duplicate_pad_numbers_are_jumpers no)
		(fp_poly
			(pts
				(xy 0.7239 -0.2159) (xy -0.7239 -0.2159) (xy -0.7239 1.9939) (xy 0.7239 1.9939)
			)
			(stroke
				(width 0)
				(type default)
			)
			(fill no)
			(layer "B.CrtYd")
		)
		(fp_line
			(start -0.7239 -0.2159)
			(end 0.7239 -0.2159)
			(stroke
				(width 0.1)
				(type default)
			)
			(layer "B.Fab")
		)
		(fp_line
			(start -0.7239 1.9939)
			(end -0.7239 -0.2159)
			(stroke
				(width 0.1)
				(type default)
			)
			(layer "B.Fab")
		)
		(fp_line
			(start 0.7239 -0.2159)
			(end 0.7239 1.9939)
			(stroke
				(width 0.1)
				(type default)
			)
			(layer "B.Fab")
		)
		(fp_line
			(start 0.7239 1.9939)
			(end -0.7239 1.9939)
			(stroke
				(width 0.1)
				(type default)
			)
			(layer "B.Fab")
		)
		(pad "1" smd rect
			(at 0 0 180)
			(size 1.27 1.016)
			(layers "B.Cu" "B.Mask" "B.Paste")
			(net "PVCCIN_CPU1")
		)
		(pad "2" smd rect
			(at 0 1.778 180)
			(size 1.27 1.016)
			(layers "B.Cu" "B.Mask" "B.Paste")
			(net "GND")
		)
		(zone
			(layer "B.Cu")
			(hatch none 0.5)
			(connect_pads
				(clearance 0)
			)
			(min_thickness 0.25)
			(keepout
				(tracks not_allowed)
				(vias allowed)
				(pads allowed)
				(copperpour not_allowed)
				(footprints allowed)
			)
			(placement
				(enabled no)
				(sheetname "")
			)
			(fill
				(thermal_gap 0.5)
				(thermal_bridge_width 0.5)
				(island_removal_mode 0)
			)
			(polygon
				(pts
					(xy 101.498654 -77.32014) (xy 100.228654 -77.32014) (xy 100.228654 -76.55814) (xy 101.498654 -76.55814)
				)
			)
		)
	)
)
